(kicad_pcb
	(version 20260206)
	(generator "pcbnew")
	(generator_version "10.0")
	(general
		(thickness 1.6)
		(legacy_teardrops no)
	)
	(paper "A4")
	(title_block
		(title "Bryce Canyon_IOM_IOC_16318-2_OCP.brd")
		(comment 1 "Bryce Canyon / footprints 1123-1130 of 1605")
	)
	(layers
		(0 "F.Cu" signal "TOP")
		(4 "In1.Cu" signal "L2GND")
		(6 "In2.Cu" signal "L3")
		(8 "In3.Cu" signal "L4VCC")
		(10 "In4.Cu" signal "L5VCC")
		(12 "In5.Cu" signal "L6")
		(14 "In6.Cu" signal "L7GND")
		(2 "B.Cu" signal "BOTTOM")
		(9 "F.Adhes" user "F.Adhesive")
		(11 "B.Adhes" user "B.Adhesive")
		(13 "F.Paste" user "Package Geometry/Pastemask Top")
		(15 "B.Paste" user "Package Geometry/Pastemask Bottom")
		(5 "F.SilkS" user "Ref Des/Silkscreen Top")
		(7 "B.SilkS" user "Ref Des/Silkscreen Bottom")
		(1 "F.Mask" user "Board Geometry/Soldermask Top")
		(3 "B.Mask" user "Board Geometry/Soldermask Bottom")
		(17 "Dwgs.User" user "User.Drawings")
		(19 "Cmts.User" user "User.Comments")
		(21 "Eco1.User" user "User.Eco1")
		(23 "Eco2.User" user "User.Eco2")
		(25 "Edge.Cuts" user "Board Geometry/Outline")
		(27 "Margin" user)
		(31 "F.CrtYd" user "Package Geometry/Place Bound Top")
		(29 "B.CrtYd" user "Package Geometry/Place Bound Bottom")
		(35 "F.Fab" user "Ref Des/Assembly Top")
		(33 "B.Fab" user "Ref Des/Assembly Bottom")
	)
	(footprint ""
		(layer "B.Cu")
		(at 37.1602 -126.4412)
		(property "Reference" "R276"
			(at 0 0 0)
			(layer "B.SilkS")
			(hide yes)
			(effects
				(font
					(size 1.27 1.27)
				)
				(justify mirror)
			)
		)
		(property "Value" "4K7R2F-GP"
			(at -0.064008 -3.993896 0)
			(unlocked yes)
			(layer "B.Fab")
			(hide yes)
			(effects
				(font
					(size 1.016 1.016)
					(thickness 0.1524)
				)
				(justify mirror)
			)
		)
		(property "Device Type" "R402H16"
			(at -0.064008 -5.517896 0)
			(unlocked yes)
			(layer "B.Fab")
			(hide yes)
			(effects
				(font
					(size 1.016 1.016)
					(thickness 0.1524)
				)
				(justify mirror)
			)
		)
		(duplicate_pad_numbers_are_jumpers no)
		(fp_line
			(start -0.508 -0.9398)
			(end 0.508 -0.9398)
			(stroke
				(width 0.1524)
				(type default)
			)
			(layer "B.SilkS")
		)
		(fp_line
			(start 0.508 -0.9398)
			(end 0.508 0.9398)
			(stroke
				(width 0.1524)
				(type default)
			)
			(layer "B.SilkS")
		)
		(fp_rect
			(start 0.508 0.9398)
			(end -0.508 -0.9398)
			(stroke
				(width 0)
				(type default)
			)
			(fill no)
			(layer "B.CrtYd")
		)
		(fp_rect
			(start 0.508 0.9398)
			(end -0.508 -0.9398)
			(stroke
				(width 0)
				(type default)
			)
			(fill no)
			(layer "B.Fab")
		)
		(pad "1" smd custom
			(at 0 -0.4445 180)
			(size 0.1397 0.1397)
			(layers "B.Cu" "B.Mask" "B.Paste")
			(net "P3V3_STBY")
			(options
				(clearance outline)
				(anchor circle)
			)
			(primitives
				(gr_poly
					(pts
						(arc
							(start -0.1778 0.2794)
							(mid -0.249642 0.249642)
							(end -0.2794 0.1778)
						)
						(arc
							(start -0.2794 -0.1778)
							(mid -0.249642 -0.249642)
							(end -0.1778 -0.2794)
						)
						(arc
							(start 0.1778 -0.2794)
							(mid 0.249642 -0.249642)
							(end 0.2794 -0.1778)
						)
						(arc
							(start 0.2794 0.1778)
							(mid 0.249642 0.249642)
							(end 0.1778 0.2794)
						)
					)
					(width 0)
					(fill yes)
				)
			)
		)
		(pad "2" smd custom
			(at 0 0.4445 180)
			(size 0.1397 0.1397)
			(layers "B.Cu" "B.Mask" "B.Paste")
			(net "DEBUG_RST_BTN_N")
			(options
				(clearance outline)
				(anchor circle)
			)
			(primitives
				(gr_poly
					(pts
						(arc
							(start -0.1778 0.2794)
							(mid -0.249642 0.249642)
							(end -0.2794 0.1778)
						)
						(arc
							(start -0.2794 -0.1778)
							(mid -0.249642 -0.249642)
							(end -0.1778 -0.2794)
						)
						(arc
							(start 0.1778 -0.2794)
							(mid 0.249642 -0.249642)
							(end 0.2794 -0.1778)
						)
						(arc
							(start 0.2794 0.1778)
							(mid 0.249642 0.249642)
							(end 0.1778 0.2794)
						)
					)
					(width 0)
					(fill yes)
				)
			)
		)
	)
	(footprint ""
		(layer "B.Cu")
		(at 196.9008 -71.0438)
		(property "Reference" "C364"
			(at 0 0 0)
			(layer "B.SilkS")
			(hide yes)
			(effects
				(font
					(size 1.27 1.27)
				)
				(justify mirror)
			)
		)
		(property "Value" "SC1U6D3V1MX-GP"
			(at -1.9177 2.0193 0)
			(unlocked yes)
			(layer "B.Fab")
			(hide yes)
			(effects
				(font
					(size 1.016 1.016)
					(thickness 0.1524)
				)
				(justify mirror)
			)
		)
		(property "Device Type" "C0201H14"
			(at -1.9177 0.4953 0)
			(unlocked yes)
			(layer "B.Fab")
			(hide yes)
			(effects
				(font
					(size 1.016 1.016)
					(thickness 0.1524)
				)
				(justify mirror)
			)
		)
		(duplicate_pad_numbers_are_jumpers no)
		(fp_rect
			(start 0.1524 0.3048)
			(end -0.1524 -0.3048)
			(stroke
				(width 0)
				(type default)
			)
			(fill no)
			(layer "B.CrtYd")
		)
		(fp_poly
			(pts
				(xy 0.2794 0.6477) (xy 0.2794 -0.6477) (xy -0.2794 -0.6477) (xy -0.2794 -0.1905) (xy -0.1524 -0.1905)
				(xy -0.1524 -0.3048) (xy 0.1524 -0.3048) (xy 0.1524 0.3048) (xy -0.1524 0.3048) (xy -0.1524 -0.1778)
				(xy -0.2794 -0.1778) (xy -0.2794 0.6477)
			)
			(stroke
				(width 0)
				(type default)
			)
			(fill no)
			(layer "B.CrtYd")
		)
		(fp_rect
			(start 0.2794 0.6477)
			(end -0.2794 -0.6477)
			(stroke
				(width 0)
				(type default)
			)
			(fill no)
			(layer "B.Fab")
		)
		(pad "1" smd custom
			(at 0 -0.2794 180)
			(size 0.0762 0.0762)
			(layers "B.Cu" "B.Mask" "B.Paste")
			(net "PCE_AVDD")
			(options
				(clearance outline)
				(anchor circle)
			)
			(primitives
				(gr_poly
					(pts
						(arc
							(start 0.1524 0.127)
							(mid 0.137521 0.162921)
							(end 0.1016 0.1778)
						)
						(arc
							(start -0.1016 0.1778)
							(mid -0.137521 0.162921)
							(end -0.1524 0.127)
						)
						(arc
							(start -0.1524 -0.127)
							(mid -0.137521 -0.162921)
							(end -0.1016 -0.1778)
						)
						(arc
							(start 0.1016 -0.1778)
							(mid 0.137521 -0.162921)
							(end 0.1524 -0.127)
						)
					)
					(width 0)
					(fill yes)
				)
			)
		)
		(pad "2" smd custom
			(at 0 0.2794 180)
			(size 0.0762 0.0762)
			(layers "B.Cu" "B.Mask" "B.Paste")
			(net "GND")
			(options
				(clearance outline)
				(anchor circle)
			)
			(primitives
				(gr_poly
					(pts
						(arc
							(start 0.1524 0.127)
							(mid 0.137521 0.162921)
							(end 0.1016 0.1778)
						)
						(arc
							(start -0.1016 0.1778)
							(mid -0.137521 0.162921)
							(end -0.1524 0.127)
						)
						(arc
							(start -0.1524 -0.127)
							(mid -0.137521 -0.162921)
							(end -0.1016 -0.1778)
						)
						(arc
							(start 0.1016 -0.1778)
							(mid 0.137521 -0.162921)
							(end 0.1524 -0.127)
						)
					)
					(width 0)
					(fill yes)
				)
			)
		)
	)
	(footprint ""
		(layer "B.Cu")
		(at 124.625862 -15.858998)
		(property "Reference" "R445"
			(at 0 0 0)
			(layer "B.SilkS")
			(hide yes)
			(effects
				(font
					(size 1.27 1.27)
				)
				(justify mirror)
			)
		)
		(property "Value" "49K9R2F-L-GP"
			(at -0.064008 -3.993896 0)
			(unlocked yes)
			(layer "B.Fab")
			(hide yes)
			(effects
				(font
					(size 1.016 1.016)
					(thickness 0.1524)
				)
				(justify mirror)
			)
		)
		(property "Device Type" "R402H16"
			(at -0.064008 -5.517896 0)
			(unlocked yes)
			(layer "B.Fab")
			(hide yes)
			(effects
				(font
					(size 1.016 1.016)
					(thickness 0.1524)
				)
				(justify mirror)
			)
		)
		(duplicate_pad_numbers_are_jumpers no)
		(fp_line
			(start -0.508 -0.9398)
			(end 0.508 -0.9398)
			(stroke
				(width 0.1524)
				(type default)
			)
			(layer "B.SilkS")
		)
		(fp_line
			(start 0.508 -0.9398)
			(end 0.508 0.9398)
			(stroke
				(width 0.1524)
				(type default)
			)
			(layer "B.SilkS")
		)
		(fp_rect
			(start 0.508 0.9398)
			(end -0.508 -0.9398)
			(stroke
				(width 0)
				(type default)
			)
			(fill no)
			(layer "B.CrtYd")
		)
		(fp_rect
			(start 0.508 0.9398)
			(end -0.508 -0.9398)
			(stroke
				(width 0)
				(type default)
			)
			(fill no)
			(layer "B.Fab")
		)
		(pad "1" smd custom
			(at 0 -0.4445 180)
			(size 0.1397 0.1397)
			(layers "B.Cu" "B.Mask" "B.Paste")
			(net "P12V_IOM")
			(options
				(clearance outline)
				(anchor circle)
			)
			(primitives
				(gr_poly
					(pts
						(arc
							(start -0.1778 0.2794)
							(mid -0.249642 0.249642)
							(end -0.2794 0.1778)
						)
						(arc
							(start -0.2794 -0.1778)
							(mid -0.249642 -0.249642)
							(end -0.1778 -0.2794)
						)
						(arc
							(start 0.1778 -0.2794)
							(mid 0.249642 -0.249642)
							(end 0.2794 -0.1778)
						)
						(arc
							(start 0.2794 0.1778)
							(mid 0.249642 0.249642)
							(end 0.1778 0.2794)
						)
					)
					(width 0)
					(fill yes)
				)
			)
		)
		(pad "2" smd custom
			(at 0 0.4445 180)
			(size 0.1397 0.1397)
			(layers "B.Cu" "B.Mask" "B.Paste")
			(net "MB0_CM_OV_R")
			(options
				(clearance outline)
				(anchor circle)
			)
			(primitives
				(gr_poly
					(pts
						(arc
							(start -0.1778 0.2794)
							(mid -0.249642 0.249642)
							(end -0.2794 0.1778)
						)
						(arc
							(start -0.2794 -0.1778)
							(mid -0.249642 -0.249642)
							(end -0.1778 -0.2794)
						)
						(arc
							(start 0.1778 -0.2794)
							(mid 0.249642 -0.249642)
							(end 0.2794 -0.1778)
						)
						(arc
							(start 0.2794 0.1778)
							(mid 0.249642 0.249642)
							(end 0.1778 0.2794)
						)
					)
					(width 0)
					(fill yes)
				)
			)
		)
	)
	(footprint ""
		(layer "B.Cu")
		(at 184.6072 -79.530702 -90)
		(property "Reference" "TP99"
			(at 0 0 90)
			(layer "B.SilkS")
			(hide yes)
			(effects
				(font
					(size 1.27 1.27)
				)
				(justify mirror)
			)
		)
		(property "Value" "TPAD28-2-GP"
			(at 0.0127 -1.6637 270)
			(unlocked yes)
			(layer "B.Fab")
			(hide yes)
			(effects
				(font
					(size 1.016 1.016)
					(thickness 0.1524)
				)
				(justify mirror)
			)
		)
		(property "Device Type" "TPAD28"
			(at 0.0127 -3.1877 270)
			(unlocked yes)
			(layer "B.Fab")
			(hide yes)
			(effects
				(font
					(size 1.016 1.016)
					(thickness 0.1524)
				)
				(justify mirror)
			)
		)
		(duplicate_pad_numbers_are_jumpers no)
		(fp_poly
			(pts
				(arc
					(start 0 -0.3556)
					(mid 0 0.3556)
					(end 0 -0.3556)
				)
			)
			(stroke
				(width 0)
				(type default)
			)
			(fill no)
			(layer "B.CrtYd")
		)
		(fp_poly
			(pts
				(arc
					(start 0 -0.6096)
					(mid 0 0.6096)
					(end 0 -0.6096)
				)
			)
			(stroke
				(width 0)
				(type default)
			)
			(fill no)
			(layer "B.Fab")
		)
		(pad "1" smd circle
			(at 0 0 90)
			(size 0.7112 0.7112)
			(layers "B.Cu" "B.Mask" "B.Paste")
			(net "IOC_GPIO_14")
		)
	)
	(footprint ""
		(layer "B.Cu")
		(at 190.6524 -124.6124)
		(property "Reference" "R562"
			(at 0 0 0)
			(layer "B.SilkS")
			(hide yes)
			(effects
				(font
					(size 1.27 1.27)
				)
				(justify mirror)
			)
		)
		(property "Value" "100KR2F-L1-GP"
			(at -0.064008 -3.993896 0)
			(unlocked yes)
			(layer "B.Fab")
			(hide yes)
			(effects
				(font
					(size 1.016 1.016)
					(thickness 0.1524)
				)
				(justify mirror)
			)
		)
		(property "Device Type" "R402H16"
			(at -0.064008 -5.517896 0)
			(unlocked yes)
			(layer "B.Fab")
			(hide yes)
			(effects
				(font
					(size 1.016 1.016)
					(thickness 0.1524)
				)
				(justify mirror)
			)
		)
		(duplicate_pad_numbers_are_jumpers no)
		(fp_line
			(start -0.508 -0.9398)
			(end 0.508 -0.9398)
			(stroke
				(width 0.1524)
				(type default)
			)
			(layer "B.SilkS")
		)
		(fp_line
			(start 0.508 -0.9398)
			(end 0.508 0.9398)
			(stroke
				(width 0.1524)
				(type default)
			)
			(layer "B.SilkS")
		)
		(fp_rect
			(start 0.508 0.9398)
			(end -0.508 -0.9398)
			(stroke
				(width 0)
				(type default)
			)
			(fill no)
			(layer "B.CrtYd")
		)
		(fp_rect
			(start 0.508 0.9398)
			(end -0.508 -0.9398)
			(stroke
				(width 0)
				(type default)
			)
			(fill no)
			(layer "B.Fab")
		)
		(pad "1" smd custom
			(at 0 -0.4445 180)
			(size 0.1397 0.1397)
			(layers "B.Cu" "B.Mask" "B.Paste")
			(net "VT235_VDES")
			(options
				(clearance outline)
				(anchor circle)
			)
			(primitives
				(gr_poly
					(pts
						(arc
							(start -0.1778 0.2794)
							(mid -0.249642 0.249642)
							(end -0.2794 0.1778)
						)
						(arc
							(start -0.2794 -0.1778)
							(mid -0.249642 -0.249642)
							(end -0.1778 -0.2794)
						)
						(arc
							(start 0.1778 -0.2794)
							(mid 0.249642 -0.249642)
							(end 0.2794 -0.1778)
						)
						(arc
							(start 0.2794 0.1778)
							(mid 0.249642 0.249642)
							(end 0.1778 0.2794)
						)
					)
					(width 0)
					(fill yes)
				)
			)
		)
		(pad "2" smd custom
			(at 0 0.4445 180)
			(size 0.1397 0.1397)
			(layers "B.Cu" "B.Mask" "B.Paste")
			(net "AVSO_VREF")
			(options
				(clearance outline)
				(anchor circle)
			)
			(primitives
				(gr_poly
					(pts
						(arc
							(start -0.1778 0.2794)
							(mid -0.249642 0.249642)
							(end -0.2794 0.1778)
						)
						(arc
							(start -0.2794 -0.1778)
							(mid -0.249642 -0.249642)
							(end -0.1778 -0.2794)
						)
						(arc
							(start 0.1778 -0.2794)
							(mid 0.249642 -0.249642)
							(end 0.2794 -0.1778)
						)
						(arc
							(start 0.2794 0.1778)
							(mid 0.249642 0.249642)
							(end 0.1778 0.2794)
						)
					)
					(width 0)
					(fill yes)
				)
			)
		)
	)
	(footprint ""
		(layer "B.Cu")
		(at 55.785258 -142.888208)
		(property "Reference" "TP54"
			(at 0 0 0)
			(layer "B.SilkS")
			(hide yes)
			(effects
				(font
					(size 1.27 1.27)
				)
				(justify mirror)
			)
		)
		(property "Value" "TPAD28-2-GP"
			(at 0.0127 -1.6637 0)
			(unlocked yes)
			(layer "B.Fab")
			(hide yes)
			(effects
				(font
					(size 1.016 1.016)
					(thickness 0.1524)
				)
				(justify mirror)
			)
		)
		(property "Device Type" "TPAD28"
			(at 0.0127 -3.1877 0)
			(unlocked yes)
			(layer "B.Fab")
			(hide yes)
			(effects
				(font
					(size 1.016 1.016)
					(thickness 0.1524)
				)
				(justify mirror)
			)
		)
		(duplicate_pad_numbers_are_jumpers no)
		(fp_poly
			(pts
				(arc
					(start 0.3556 0)
					(mid -0.3556 0)
					(end 0.3556 0)
				)
			)
			(stroke
				(width 0)
				(type default)
			)
			(fill no)
			(layer "B.CrtYd")
		)
		(fp_poly
			(pts
				(arc
					(start 0.6096 0)
					(mid -0.6096 0)
					(end 0.6096 0)
				)
			)
			(stroke
				(width 0)
				(type default)
			)
			(fill no)
			(layer "B.Fab")
		)
		(pad "1" smd circle
			(at 0 0 180)
			(size 0.7112 0.7112)
			(layers "B.Cu" "B.Mask" "B.Paste")
			(net "TP_BMC_GPIOA6")
		)
	)
	(footprint ""
		(layer "B.Cu")
		(at 197.9168 -54.5338 90)
		(property "Reference" "C438"
			(at 0 0 90)
			(layer "B.SilkS")
			(hide yes)
			(effects
				(font
					(size 1.27 1.27)
				)
				(justify mirror)
			)
		)
		(property "Value" "SCD1U16V2KX-3GP"
			(at -1.1811 -2.7051 90)
			(unlocked yes)
			(layer "B.Fab")
			(hide yes)
			(effects
				(font
					(size 1.016 1.016)
					(thickness 0.1524)
				)
				(justify mirror)
			)
		)
		(property "Device Type" "C402H22"
			(at -1.1811 -4.2291 90)
			(unlocked yes)
			(layer "B.Fab")
			(hide yes)
			(effects
				(font
					(size 1.016 1.016)
					(thickness 0.1524)
				)
				(justify mirror)
			)
		)
		(duplicate_pad_numbers_are_jumpers no)
		(fp_rect
			(start 0.4318 0.9525)
			(end -0.4318 -0.9525)
			(stroke
				(width 0)
				(type default)
			)
			(fill no)
			(layer "B.CrtYd")
		)
		(fp_rect
			(start 0.4318 0.9525)
			(end -0.4318 -0.9525)
			(stroke
				(width 0)
				(type default)
			)
			(fill no)
			(layer "B.Fab")
		)
		(pad "1" smd custom
			(at 0 -0.4445 270)
			(size 0.1524 0.1524)
			(layers "B.Cu" "B.Mask" "B.Paste")
			(net "P1V8")
			(options
				(clearance outline)
				(anchor circle)
			)
			(primitives
				(gr_poly
					(pts
						(arc
							(start 0.3048 0.2032)
							(mid 0.275042 0.275042)
							(end 0.2032 0.3048)
						)
						(arc
							(start -0.2032 0.3048)
							(mid -0.275042 0.275042)
							(end -0.3048 0.2032)
						)
						(arc
							(start -0.3048 -0.2032)
							(mid -0.275042 -0.275042)
							(end -0.2032 -0.3048)
						)
						(arc
							(start 0.2032 -0.3048)
							(mid 0.275042 -0.275042)
							(end 0.3048 -0.2032)
						)
					)
					(width 0)
					(fill yes)
				)
			)
		)
		(pad "2" smd custom
			(at 0 0.4445 270)
			(size 0.1524 0.1524)
			(layers "B.Cu" "B.Mask" "B.Paste")
			(net "GND")
			(options
				(clearance outline)
				(anchor circle)
			)
			(primitives
				(gr_poly
					(pts
						(arc
							(start 0.3048 0.2032)
							(mid 0.275042 0.275042)
							(end 0.2032 0.3048)
						)
						(arc
							(start -0.2032 0.3048)
							(mid -0.275042 0.275042)
							(end -0.3048 0.2032)
						)
						(arc
							(start -0.3048 -0.2032)
							(mid -0.275042 -0.275042)
							(end -0.2032 -0.3048)
						)
						(arc
							(start 0.2032 -0.3048)
							(mid 0.275042 -0.275042)
							(end 0.3048 -0.2032)
						)
					)
					(width 0)
					(fill yes)
				)
			)
		)
	)
	(footprint ""
		(layer "B.Cu")
		(at 185.96864 -58.63336 90)
		(property "Reference" "C444"
			(at 0 0 90)
			(layer "B.SilkS")
			(hide yes)
			(effects
				(font
					(size 1.27 1.27)
				)
				(justify mirror)
			)
		)
		(property "Value" "SCD1U16V2KX-3GP"
			(at -1.1811 -2.7051 90)
			(unlocked yes)
			(layer "B.Fab")
			(hide yes)
			(effects
				(font
					(size 1.016 1.016)
					(thickness 0.1524)
				)
				(justify mirror)
			)
		)
		(property "Device Type" "C402H22"
			(at -1.1811 -4.2291 90)
			(unlocked yes)
			(layer "B.Fab")
			(hide yes)
			(effects
				(font
					(size 1.016 1.016)
					(thickness 0.1524)
				)
				(justify mirror)
			)
		)
		(duplicate_pad_numbers_are_jumpers no)
		(fp_rect
			(start 0.4318 0.9525)
			(end -0.4318 -0.9525)
			(stroke
				(width 0)
				(type default)
			)
			(fill no)
			(layer "B.CrtYd")
		)
		(fp_rect
			(start 0.4318 0.9525)
			(end -0.4318 -0.9525)
			(stroke
				(width 0)
				(type default)
			)
			(fill no)
			(layer "B.Fab")
		)
		(pad "1" smd custom
			(at 0 -0.4445 270)
			(size 0.1524 0.1524)
			(layers "B.Cu" "B.Mask" "B.Paste")
			(net "P1V8")
			(options
				(clearance outline)
				(anchor circle)
			)
			(primitives
				(gr_poly
					(pts
						(arc
							(start 0.3048 0.2032)
							(mid 0.275042 0.275042)
							(end 0.2032 0.3048)
						)
						(arc
							(start -0.2032 0.3048)
							(mid -0.275042 0.275042)
							(end -0.3048 0.2032)
						)
						(arc
							(start -0.3048 -0.2032)
							(mid -0.275042 -0.275042)
							(end -0.2032 -0.3048)
						)
						(arc
							(start 0.2032 -0.3048)
							(mid 0.275042 -0.275042)
							(end 0.3048 -0.2032)
						)
					)
					(width 0)
					(fill yes)
				)
			)
		)
		(pad "2" smd custom
			(at 0 0.4445 270)
			(size 0.1524 0.1524)
			(layers "B.Cu" "B.Mask" "B.Paste")
			(net "GND")
			(options
				(clearance outline)
				(anchor circle)
			)
			(primitives
				(gr_poly
					(pts
						(arc
							(start 0.3048 0.2032)
							(mid 0.275042 0.275042)
							(end 0.2032 0.3048)
						)
						(arc
							(start -0.2032 0.3048)
							(mid -0.275042 0.275042)
							(end -0.3048 0.2032)
						)
						(arc
							(start -0.3048 -0.2032)
							(mid -0.275042 -0.275042)
							(end -0.2032 -0.3048)
						)
						(arc
							(start 0.2032 -0.3048)
							(mid 0.275042 -0.275042)
							(end 0.3048 -0.2032)
						)
					)
					(width 0)
					(fill yes)
				)
			)
		)
	)
)
